(kicad_pcb
	(version 20260206)
	(generator "pcbnew")
	(generator_version "10.0")
	(general
		(thickness 1.6)
		(legacy_teardrops no)
	)
	(paper "A4")
	(title_block
		(title "01162023_DA0F0TEBIF0_F0T_Expander_BD_F_brd_V02_OCP.brd")
		(comment 1 "Grand Teton / footprints 2415-2420 of 9728")
	)
	(layers
		(0 "F.Cu" signal "TOP")
		(4 "In1.Cu" signal "GND")
		(6 "In2.Cu" signal "VCC")
		(8 "In3.Cu" signal "VCC1")
		(10 "In4.Cu" signal "GND1")
		(12 "In5.Cu" signal "IN1")
		(14 "In6.Cu" signal "GND2")
		(16 "In7.Cu" signal "IN2")
		(18 "In8.Cu" signal "GND3")
		(20 "In9.Cu" signal "IN3")
		(22 "In10.Cu" signal "GND4")
		(24 "In11.Cu" signal "IN4")
		(26 "In12.Cu" signal "GND5")
		(28 "In13.Cu" signal "IN5")
		(30 "In14.Cu" signal "GND6")
		(32 "In15.Cu" signal "IN6")
		(34 "In16.Cu" signal "GND7")
		(2 "B.Cu" signal "BOTTOM")
		(9 "F.Adhes" user "F.Adhesive")
		(11 "B.Adhes" user "B.Adhesive")
		(13 "F.Paste" user "Package Geometry/Pastemask Top")
		(15 "B.Paste" user "Package Geometry/Pastemask Bottom")
		(5 "F.SilkS" user "Ref Des/Silkscreen Top")
		(7 "B.SilkS" user "Ref Des/Silkscreen Bottom")
		(1 "F.Mask" user "Board Geometry/Soldermask Top")
		(3 "B.Mask" user "Board Geometry/Soldermask Bottom")
		(17 "Dwgs.User" user "User.Drawings")
		(19 "Cmts.User" user "User.Comments")
		(21 "Eco1.User" user "User.Eco1")
		(23 "Eco2.User" user "User.Eco2")
		(25 "Edge.Cuts" user "Board Geometry/Outline")
		(27 "Margin" user)
		(31 "F.CrtYd" user "Package Geometry/Place Bound Top")
		(29 "B.CrtYd" user "Package Geometry/Place Bound Bottom")
		(35 "F.Fab" user "Ref Des/Assembly Top")
		(33 "B.Fab" user "Ref Des/Assembly Bottom")
	)
	(footprint ""
		(layer "F.Cu")
		(at 178.908456 -158.080202 90)
		(property "Reference" "R2473"
			(at 0 0 90)
			(layer "F.SilkS")
			(hide yes)
			(effects
				(font
					(size 1.27 1.27)
				)
			)
		)
		(property "Value" ""
			(at 0 0 90)
			(layer "F.Fab")
			(effects
				(font
					(size 1.27 1.27)
				)
			)
		)
		(duplicate_pad_numbers_are_jumpers no)
		(fp_line
			(start 0.7874 -0.4064)
			(end 0.7874 0.4064)
			(stroke
				(width 0.1524)
				(type default)
			)
			(layer "F.SilkS")
		)
		(fp_line
			(start -0.7874 -0.4064)
			(end 0.7874 -0.4064)
			(stroke
				(width 0.1524)
				(type default)
			)
			(layer "F.SilkS")
		)
		(fp_line
			(start 0.7874 0.4064)
			(end -0.7874 0.4064)
			(stroke
				(width 0.1524)
				(type default)
			)
			(layer "F.SilkS")
		)
		(fp_line
			(start -0.7874 0.4064)
			(end -0.7874 -0.4064)
			(stroke
				(width 0.1524)
				(type default)
			)
			(layer "F.SilkS")
		)
		(fp_line
			(start -0.12065 -0.305054)
			(end -0.12065 -0.2794)
			(stroke
				(width 0.1)
				(type default)
			)
			(layer "F.Fab")
		)
		(fp_line
			(start -0.67945 -0.305054)
			(end -0.12065 -0.305054)
			(stroke
				(width 0.1)
				(type default)
			)
			(layer "F.Fab")
		)
		(fp_line
			(start 0.67945 -0.3048)
			(end 0.67945 0.3048)
			(stroke
				(width 0.1)
				(type default)
			)
			(layer "F.Fab")
		)
		(fp_line
			(start 0.12065 -0.3048)
			(end 0.67945 -0.3048)
			(stroke
				(width 0.1)
				(type default)
			)
			(layer "F.Fab")
		)
		(fp_line
			(start 0.12065 -0.2794)
			(end 0.12065 -0.3048)
			(stroke
				(width 0.1)
				(type default)
			)
			(layer "F.Fab")
		)
		(fp_line
			(start -0.12065 -0.2794)
			(end 0.12065 -0.2794)
			(stroke
				(width 0.1)
				(type default)
			)
			(layer "F.Fab")
		)
		(fp_line
			(start 0.120396 0.2794)
			(end -0.12065 0.2794)
			(stroke
				(width 0.1)
				(type default)
			)
			(layer "F.Fab")
		)
		(fp_line
			(start -0.12065 0.2794)
			(end -0.12065 0.3048)
			(stroke
				(width 0.1)
				(type default)
			)
			(layer "F.Fab")
		)
		(fp_line
			(start 0.67945 0.3048)
			(end 0.120396 0.3048)
			(stroke
				(width 0.1)
				(type default)
			)
			(layer "F.Fab")
		)
		(fp_line
			(start 0.120396 0.3048)
			(end 0.120396 0.2794)
			(stroke
				(width 0.1)
				(type default)
			)
			(layer "F.Fab")
		)
		(fp_line
			(start -0.12065 0.3048)
			(end -0.67945 0.3048)
			(stroke
				(width 0.1)
				(type default)
			)
			(layer "F.Fab")
		)
		(fp_line
			(start -0.67945 0.3048)
			(end -0.67945 -0.305054)
			(stroke
				(width 0.1)
				(type default)
			)
			(layer "F.Fab")
		)
		(pad "1" smd circle
			(at -0.40005 0 90)
			(size 0 0)
			(layers "F.Cu" "F.Mask" "F.Paste")
			(net "P3V3_NIC3")
		)
		(pad "2" smd circle
			(at 0.40005 0 90)
			(size 0 0)
			(layers "F.Cu" "F.Mask" "F.Paste")
			(net "NIC3_PWRBRK_N")
		)
	)
	(footprint ""
		(layer "F.Cu")
		(at 254.062992 -259.819394 -90)
		(property "Reference" "R1391"
			(at 0 0 270)
			(layer "F.SilkS")
			(hide yes)
			(effects
				(font
					(size 1.27 1.27)
				)
			)
		)
		(property "Value" ""
			(at 0 0 270)
			(layer "F.Fab")
			(effects
				(font
					(size 1.27 1.27)
				)
			)
		)
		(duplicate_pad_numbers_are_jumpers no)
		(fp_line
			(start -0.7874 0.4064)
			(end -0.7874 -0.4064)
			(stroke
				(width 0.1524)
				(type default)
			)
			(layer "F.SilkS")
		)
		(fp_line
			(start 0.7874 0.4064)
			(end -0.7874 0.4064)
			(stroke
				(width 0.1524)
				(type default)
			)
			(layer "F.SilkS")
		)
		(fp_line
			(start -0.7874 -0.4064)
			(end 0.7874 -0.4064)
			(stroke
				(width 0.1524)
				(type default)
			)
			(layer "F.SilkS")
		)
		(fp_line
			(start 0.7874 -0.4064)
			(end 0.7874 0.4064)
			(stroke
				(width 0.1524)
				(type default)
			)
			(layer "F.SilkS")
		)
		(fp_line
			(start -0.67945 0.3048)
			(end -0.67945 -0.305054)
			(stroke
				(width 0.1)
				(type default)
			)
			(layer "F.Fab")
		)
		(fp_line
			(start -0.12065 0.3048)
			(end -0.67945 0.3048)
			(stroke
				(width 0.1)
				(type default)
			)
			(layer "F.Fab")
		)
		(fp_line
			(start 0.120396 0.3048)
			(end 0.120396 0.2794)
			(stroke
				(width 0.1)
				(type default)
			)
			(layer "F.Fab")
		)
		(fp_line
			(start 0.67945 0.3048)
			(end 0.120396 0.3048)
			(stroke
				(width 0.1)
				(type default)
			)
			(layer "F.Fab")
		)
		(fp_line
			(start -0.12065 0.2794)
			(end -0.12065 0.3048)
			(stroke
				(width 0.1)
				(type default)
			)
			(layer "F.Fab")
		)
		(fp_line
			(start 0.120396 0.2794)
			(end -0.12065 0.2794)
			(stroke
				(width 0.1)
				(type default)
			)
			(layer "F.Fab")
		)
		(fp_line
			(start -0.12065 -0.2794)
			(end 0.12065 -0.2794)
			(stroke
				(width 0.1)
				(type default)
			)
			(layer "F.Fab")
		)
		(fp_line
			(start 0.12065 -0.2794)
			(end 0.12065 -0.3048)
			(stroke
				(width 0.1)
				(type default)
			)
			(layer "F.Fab")
		)
		(fp_line
			(start 0.12065 -0.3048)
			(end 0.67945 -0.3048)
			(stroke
				(width 0.1)
				(type default)
			)
			(layer "F.Fab")
		)
		(fp_line
			(start 0.67945 -0.3048)
			(end 0.67945 0.3048)
			(stroke
				(width 0.1)
				(type default)
			)
			(layer "F.Fab")
		)
		(fp_line
			(start -0.67945 -0.305054)
			(end -0.12065 -0.305054)
			(stroke
				(width 0.1)
				(type default)
			)
			(layer "F.Fab")
		)
		(fp_line
			(start -0.12065 -0.305054)
			(end -0.12065 -0.2794)
			(stroke
				(width 0.1)
				(type default)
			)
			(layer "F.Fab")
		)
		(pad "1" smd circle
			(at -0.40005 0 270)
			(size 0 0)
			(layers "F.Cu" "F.Mask" "F.Paste")
			(net "PEX2_SYS_ERR_N")
		)
		(pad "2" smd circle
			(at 0.40005 0 270)
			(size 0 0)
			(layers "F.Cu" "F.Mask" "F.Paste")
			(net "PEX2_SYS_ERR_R_N")
		)
	)
	(footprint ""
		(layer "F.Cu")
		(at 269.204694 -142.88897 180)
		(property "Reference" "R233"
			(at 0 0 180)
			(layer "F.SilkS")
			(hide yes)
			(effects
				(font
					(size 1.27 1.27)
				)
			)
		)
		(property "Value" ""
			(at 0 0 180)
			(layer "F.Fab")
			(effects
				(font
					(size 1.27 1.27)
				)
			)
		)
		(duplicate_pad_numbers_are_jumpers no)
		(fp_line
			(start 0.7874 0.4064)
			(end -0.7874 0.4064)
			(stroke
				(width 0.1524)
				(type default)
			)
			(layer "F.SilkS")
		)
		(fp_line
			(start 0.7874 -0.4064)
			(end 0.7874 0.4064)
			(stroke
				(width 0.1524)
				(type default)
			)
			(layer "F.SilkS")
		)
		(fp_line
			(start -0.7874 0.4064)
			(end -0.7874 -0.4064)
			(stroke
				(width 0.1524)
				(type default)
			)
			(layer "F.SilkS")
		)
		(fp_line
			(start -0.7874 -0.4064)
			(end 0.7874 -0.4064)
			(stroke
				(width 0.1524)
				(type default)
			)
			(layer "F.SilkS")
		)
		(fp_line
			(start 0.67945 0.3048)
			(end 0.120396 0.3048)
			(stroke
				(width 0.1)
				(type default)
			)
			(layer "F.Fab")
		)
		(fp_line
			(start 0.67945 -0.3048)
			(end 0.67945 0.3048)
			(stroke
				(width 0.1)
				(type default)
			)
			(layer "F.Fab")
		)
		(fp_line
			(start 0.12065 -0.2794)
			(end 0.12065 -0.3048)
			(stroke
				(width 0.1)
				(type default)
			)
			(layer "F.Fab")
		)
		(fp_line
			(start 0.12065 -0.3048)
			(end 0.67945 -0.3048)
			(stroke
				(width 0.1)
				(type default)
			)
			(layer "F.Fab")
		)
		(fp_line
			(start 0.120396 0.3048)
			(end 0.120396 0.2794)
			(stroke
				(width 0.1)
				(type default)
			)
			(layer "F.Fab")
		)
		(fp_line
			(start 0.120396 0.2794)
			(end -0.12065 0.2794)
			(stroke
				(width 0.1)
				(type default)
			)
			(layer "F.Fab")
		)
		(fp_line
			(start -0.12065 0.3048)
			(end -0.67945 0.3048)
			(stroke
				(width 0.1)
				(type default)
			)
			(layer "F.Fab")
		)
		(fp_line
			(start -0.12065 0.2794)
			(end -0.12065 0.3048)
			(stroke
				(width 0.1)
				(type default)
			)
			(layer "F.Fab")
		)
		(fp_line
			(start -0.12065 -0.2794)
			(end 0.12065 -0.2794)
			(stroke
				(width 0.1)
				(type default)
			)
			(layer "F.Fab")
		)
		(fp_line
			(start -0.12065 -0.305054)
			(end -0.12065 -0.2794)
			(stroke
				(width 0.1)
				(type default)
			)
			(layer "F.Fab")
		)
		(fp_line
			(start -0.67945 0.3048)
			(end -0.67945 -0.305054)
			(stroke
				(width 0.1)
				(type default)
			)
			(layer "F.Fab")
		)
		(fp_line
			(start -0.67945 -0.305054)
			(end -0.12065 -0.305054)
			(stroke
				(width 0.1)
				(type default)
			)
			(layer "F.Fab")
		)
		(pad "1" smd circle
			(at -0.40005 0 180)
			(size 0 0)
			(layers "F.Cu" "F.Mask" "F.Paste")
			(net "NIC4_BIF0_N")
		)
		(pad "2" smd circle
			(at 0.40005 0 180)
			(size 0 0)
			(layers "F.Cu" "F.Mask" "F.Paste")
			(net "P3V3_AUX")
		)
	)
	(footprint ""
		(layer "F.Cu")
		(at 246.153686 -115.147852 -90)
		(property "Reference" "PC899"
			(at 0 0 270)
			(layer "F.SilkS")
			(hide yes)
			(effects
				(font
					(size 1.27 1.27)
				)
			)
		)
		(property "Value" ""
			(at 0 0 270)
			(layer "F.Fab")
			(effects
				(font
					(size 1.27 1.27)
				)
			)
		)
		(duplicate_pad_numbers_are_jumpers no)
		(fp_line
			(start -0.7874 0.4064)
			(end -0.7874 -0.4064)
			(stroke
				(width 0.1524)
				(type default)
			)
			(layer "F.SilkS")
		)
		(fp_line
			(start 0.7874 0.4064)
			(end -0.7874 0.4064)
			(stroke
				(width 0.1524)
				(type default)
			)
			(layer "F.SilkS")
		)
		(fp_line
			(start -0.7874 -0.4064)
			(end 0.7874 -0.4064)
			(stroke
				(width 0.1524)
				(type default)
			)
			(layer "F.SilkS")
		)
		(fp_line
			(start 0.7874 -0.4064)
			(end 0.7874 0.4064)
			(stroke
				(width 0.1524)
				(type default)
			)
			(layer "F.SilkS")
		)
		(fp_line
			(start -0.67945 0.3048)
			(end -0.67945 -0.305054)
			(stroke
				(width 0.1)
				(type default)
			)
			(layer "F.Fab")
		)
		(fp_line
			(start -0.12065 0.3048)
			(end -0.67945 0.3048)
			(stroke
				(width 0.1)
				(type default)
			)
			(layer "F.Fab")
		)
		(fp_line
			(start 0.120396 0.3048)
			(end 0.120396 0.2794)
			(stroke
				(width 0.1)
				(type default)
			)
			(layer "F.Fab")
		)
		(fp_line
			(start 0.67945 0.3048)
			(end 0.120396 0.3048)
			(stroke
				(width 0.1)
				(type default)
			)
			(layer "F.Fab")
		)
		(fp_line
			(start -0.12065 0.2794)
			(end -0.12065 0.3048)
			(stroke
				(width 0.1)
				(type default)
			)
			(layer "F.Fab")
		)
		(fp_line
			(start 0.120396 0.2794)
			(end -0.12065 0.2794)
			(stroke
				(width 0.1)
				(type default)
			)
			(layer "F.Fab")
		)
		(fp_line
			(start -0.12065 -0.2794)
			(end 0.12065 -0.2794)
			(stroke
				(width 0.1)
				(type default)
			)
			(layer "F.Fab")
		)
		(fp_line
			(start 0.12065 -0.2794)
			(end 0.12065 -0.3048)
			(stroke
				(width 0.1)
				(type default)
			)
			(layer "F.Fab")
		)
		(fp_line
			(start 0.12065 -0.3048)
			(end 0.67945 -0.3048)
			(stroke
				(width 0.1)
				(type default)
			)
			(layer "F.Fab")
		)
		(fp_line
			(start 0.67945 -0.3048)
			(end 0.67945 0.3048)
			(stroke
				(width 0.1)
				(type default)
			)
			(layer "F.Fab")
		)
		(fp_line
			(start -0.67945 -0.305054)
			(end -0.12065 -0.305054)
			(stroke
				(width 0.1)
				(type default)
			)
			(layer "F.Fab")
		)
		(fp_line
			(start -0.12065 -0.305054)
			(end -0.12065 -0.2794)
			(stroke
				(width 0.1)
				(type default)
			)
			(layer "F.Fab")
		)
		(pad "1" smd circle
			(at -0.40005 0 270)
			(size 0 0)
			(layers "F.Cu" "F.Mask" "F.Paste")
			(net "P3V3_AUX")
		)
		(pad "2" smd circle
			(at 0.40005 0 270)
			(size 0 0)
			(layers "F.Cu" "F.Mask" "F.Paste")
			(net "GND")
		)
	)
	(footprint ""
		(layer "F.Cu")
		(at 94.103444 -96.811592 90)
		(property "Reference" "R698"
			(at 0 0 90)
			(layer "F.SilkS")
			(hide yes)
			(effects
				(font
					(size 1.27 1.27)
				)
			)
		)
		(property "Value" ""
			(at 0 0 90)
			(layer "F.Fab")
			(effects
				(font
					(size 1.27 1.27)
				)
			)
		)
		(duplicate_pad_numbers_are_jumpers no)
		(fp_line
			(start 0.7874 -0.4064)
			(end 0.7874 0.4064)
			(stroke
				(width 0.1524)
				(type default)
			)
			(layer "F.SilkS")
		)
		(fp_line
			(start -0.7874 -0.4064)
			(end 0.7874 -0.4064)
			(stroke
				(width 0.1524)
				(type default)
			)
			(layer "F.SilkS")
		)
		(fp_line
			(start 0.7874 0.4064)
			(end -0.7874 0.4064)
			(stroke
				(width 0.1524)
				(type default)
			)
			(layer "F.SilkS")
		)
		(fp_line
			(start -0.7874 0.4064)
			(end -0.7874 -0.4064)
			(stroke
				(width 0.1524)
				(type default)
			)
			(layer "F.SilkS")
		)
		(fp_line
			(start -0.12065 -0.305054)
			(end -0.12065 -0.2794)
			(stroke
				(width 0.1)
				(type default)
			)
			(layer "F.Fab")
		)
		(fp_line
			(start -0.67945 -0.305054)
			(end -0.12065 -0.305054)
			(stroke
				(width 0.1)
				(type default)
			)
			(layer "F.Fab")
		)
		(fp_line
			(start 0.67945 -0.3048)
			(end 0.67945 0.3048)
			(stroke
				(width 0.1)
				(type default)
			)
			(layer "F.Fab")
		)
		(fp_line
			(start 0.12065 -0.3048)
			(end 0.67945 -0.3048)
			(stroke
				(width 0.1)
				(type default)
			)
			(layer "F.Fab")
		)
		(fp_line
			(start 0.12065 -0.2794)
			(end 0.12065 -0.3048)
			(stroke
				(width 0.1)
				(type default)
			)
			(layer "F.Fab")
		)
		(fp_line
			(start -0.12065 -0.2794)
			(end 0.12065 -0.2794)
			(stroke
				(width 0.1)
				(type default)
			)
			(layer "F.Fab")
		)
		(fp_line
			(start 0.120396 0.2794)
			(end -0.12065 0.2794)
			(stroke
				(width 0.1)
				(type default)
			)
			(layer "F.Fab")
		)
		(fp_line
			(start -0.12065 0.2794)
			(end -0.12065 0.3048)
			(stroke
				(width 0.1)
				(type default)
			)
			(layer "F.Fab")
		)
		(fp_line
			(start 0.67945 0.3048)
			(end 0.120396 0.3048)
			(stroke
				(width 0.1)
				(type default)
			)
			(layer "F.Fab")
		)
		(fp_line
			(start 0.120396 0.3048)
			(end 0.120396 0.2794)
			(stroke
				(width 0.1)
				(type default)
			)
			(layer "F.Fab")
		)
		(fp_line
			(start -0.12065 0.3048)
			(end -0.67945 0.3048)
			(stroke
				(width 0.1)
				(type default)
			)
			(layer "F.Fab")
		)
		(fp_line
			(start -0.67945 0.3048)
			(end -0.67945 -0.305054)
			(stroke
				(width 0.1)
				(type default)
			)
			(layer "F.Fab")
		)
		(pad "1" smd circle
			(at -0.40005 0 90)
			(size 0 0)
			(layers "F.Cu" "F.Mask" "F.Paste")
			(net "SMB_BIC_I2C6_MUX_NIC_ADC_R_SCL")
		)
		(pad "2" smd circle
			(at 0.40005 0 90)
			(size 0 0)
			(layers "F.Cu" "F.Mask" "F.Paste")
			(net "SMB_NIC1_ADC_SCL")
		)
	)
	(footprint ""
		(layer "F.Cu")
		(at 72.255126 -35.876738)
		(property "Reference" "R5881"
			(at 0 0 0)
			(layer "F.SilkS")
			(hide yes)
			(effects
				(font
					(size 1.27 1.27)
				)
			)
		)
		(property "Value" ""
			(at 0 0 0)
			(layer "F.Fab")
			(effects
				(font
					(size 1.27 1.27)
				)
			)
		)
		(duplicate_pad_numbers_are_jumpers no)
		(fp_line
			(start -0.7874 -0.4064)
			(end 0.7874 -0.4064)
			(stroke
				(width 0.1524)
				(type default)
			)
			(layer "F.SilkS")
		)
		(fp_line
			(start -0.7874 0.4064)
			(end -0.7874 -0.4064)
			(stroke
				(width 0.1524)
				(type default)
			)
			(layer "F.SilkS")
		)
		(fp_line
			(start 0.7874 -0.4064)
			(end 0.7874 0.4064)
			(stroke
				(width 0.1524)
				(type default)
			)
			(layer "F.SilkS")
		)
		(fp_line
			(start 0.7874 0.4064)
			(end -0.7874 0.4064)
			(stroke
				(width 0.1524)
				(type default)
			)
			(layer "F.SilkS")
		)
		(fp_line
			(start -0.67945 -0.305054)
			(end -0.12065 -0.305054)
			(stroke
				(width 0.1)
				(type default)
			)
			(layer "F.Fab")
		)
		(fp_line
			(start -0.67945 0.3048)
			(end -0.67945 -0.305054)
			(stroke
				(width 0.1)
				(type default)
			)
			(layer "F.Fab")
		)
		(fp_line
			(start -0.12065 -0.305054)
			(end -0.12065 -0.2794)
			(stroke
				(width 0.1)
				(type default)
			)
			(layer "F.Fab")
		)
		(fp_line
			(start -0.12065 -0.2794)
			(end 0.12065 -0.2794)
			(stroke
				(width 0.1)
				(type default)
			)
			(layer "F.Fab")
		)
		(fp_line
			(start -0.12065 0.2794)
			(end -0.12065 0.3048)
			(stroke
				(width 0.1)
				(type default)
			)
			(layer "F.Fab")
		)
		(fp_line
			(start -0.12065 0.3048)
			(end -0.67945 0.3048)
			(stroke
				(width 0.1)
				(type default)
			)
			(layer "F.Fab")
		)
		(fp_line
			(start 0.120396 0.2794)
			(end -0.12065 0.2794)
			(stroke
				(width 0.1)
				(type default)
			)
			(layer "F.Fab")
		)
		(fp_line
			(start 0.120396 0.3048)
			(end 0.120396 0.2794)
			(stroke
				(width 0.1)
				(type default)
			)
			(layer "F.Fab")
		)
		(fp_line
			(start 0.12065 -0.3048)
			(end 0.67945 -0.3048)
			(stroke
				(width 0.1)
				(type default)
			)
			(layer "F.Fab")
		)
		(fp_line
			(start 0.12065 -0.2794)
			(end 0.12065 -0.3048)
			(stroke
				(width 0.1)
				(type default)
			)
			(layer "F.Fab")
		)
		(fp_line
			(start 0.67945 -0.3048)
			(end 0.67945 0.3048)
			(stroke
				(width 0.1)
				(type default)
			)
			(layer "F.Fab")
		)
		(fp_line
			(start 0.67945 0.3048)
			(end 0.120396 0.3048)
			(stroke
				(width 0.1)
				(type default)
			)
			(layer "F.Fab")
		)
		(pad "1" smd circle
			(at -0.40005 0)
			(size 0 0)
			(layers "F.Cu" "F.Mask" "F.Paste")
			(net "P3V3_AUX")
		)
		(pad "2" smd circle
			(at 0.40005 0)
			(size 0 0)
			(layers "F.Cu" "F.Mask" "F.Paste")
			(net "PWRGD_P3V3_SSD3_D")
		)
	)
)
